# T6G (Grand Teton) — schematic netlist excerpt (pin names and nets, part order shuffled) for the footprints in the layout excerpt that follows; sources: Cadence DE-HDL packaged netlist, KiCad conversion of 04192023_DAF0TMB3IC0_F0TG_MB_C_brd_V02_OCP.brd

J16  SCONN288_DDR506112002KQ  IO  pkg DDR288S_1-1VXC  page 92
  VIN_BULK0  = P12V_MEM_CPU0
  RFU0  = NC
  VIN_MGMT  = P3V3_AUX
  HSCL  = I3C_SPD_DDRG_CPU0_SCL
  HSDA  = I3C_SPD_DDRG_CPU0_SDA
  VSS0  = GND
  DQ0_A  = M_G_CPU0_SA_DQ<0>
  VSS1  = GND
  DQ1_A  = M_G_CPU0_SA_DQ<1>
  VSS2  = GND
  DQS0_A_T  = M_G_CPU0_SA_DQS_DP<0>
  DQS0_A_C  = M_G_CPU0_SA_DQS_DN<0>
  VSS3  = GND
  DQ4_A  = M_G_CPU0_SA_DQ<4>
  VSS4  = GND
  DQ5_A  = M_G_CPU0_SA_DQ<5>
  VSS5  = GND
  DQ8_A  = M_G_CPU0_SA_DQ<8>
  VSS6  = GND
  DQ9_A  = M_G_CPU0_SA_DQ<9>
  VSS7  = GND
  DQS1_A_T  = M_G_CPU0_SA_DQS_DP<1>
  DQS1_A_C  = M_G_CPU0_SA_DQS_DN<1>
  VSS8  = GND
  DQ12_A  = M_G_CPU0_SA_DQ<12>
  VSS9  = GND
  DQ13_A  = M_G_CPU0_SA_DQ<13>
  VSS10  = GND
  DQ16_A  = M_G_CPU0_SA_DQ<16>
  VSS11  = GND
  DQ17_A  = M_G_CPU0_SA_DQ<17>
  VSS12  = GND
  DQS2_A_T  = M_G_CPU0_SA_DQS_DP<2>
  DQS2_A_C  = M_G_CPU0_SA_DQS_DN<2>
  VSS13  = GND
  DQ20_A  = M_G_CPU0_SA_DQ<20>
  VSS14  = GND
  DQ21_A  = M_G_CPU0_SA_DQ<21>
  VSS15  = GND
  DQ24_A  = M_G_CPU0_SA_DQ<24>
  VSS16  = GND
  DQ25_A  = M_G_CPU0_SA_DQ<25>
  VSS17  = GND
  DQS3_A_T  = M_G_CPU0_SA_DQS_DP<3>
  DQS3_A_C  = M_G_CPU0_SA_DQS_DN<3>
  VSS18  = GND
  DQ28_A  = M_G_CPU0_SA_DQ<28>
  VSS19  = GND
  DQ29_A  = M_G_CPU0_SA_DQ<29>
  VSS20  = GND
  CB0_A  = M_G_CPU0_SA_CB<0>
  VSS21  = GND
  CB1_A  = M_G_CPU0_SA_CB<1>
  VSS22  = GND
  DQS4_A_T  = M_G_CPU0_SA_DQS_DP<4>
  DQS4_A_C  = M_G_CPU0_SA_DQS_DN<4>
  VSS23  = GND
  CB4_A  = M_G_CPU0_SA_CB<4>
  VSS24  = GND
  CB5_A  = M_G_CPU0_SA_CB<5>
  VSS25  = GND
  ALERT_N  = M_G_CPU0_ALERT_N
  VSS26  = GND
  CS0_A_N  = M_G_CPU0_SA_CS_N<0>
  VSS27  = GND
  CA0_A  = M_G_CPU0_SA_CA<0>
  VSS28  = GND
  CA2_A  = M_G_CPU0_SA_CA<2>
  VSS29  = GND
  CA4_A  = M_G_CPU0_SA_CA<4>
  VSS30  = GND
  CA6_A  = M_G_CPU0_SA_CA<6>
  VSS31  = GND
  PAR_A  = M_G_CPU0_SA_PAR
  VSS32  = GND
  CA0_B  = M_G_CPU0_SB_CA<0>
  VSS33  = GND
  CA2_B  = M_G_CPU0_SB_CA<2>
  VSS34  = GND
  CA4_B  = M_G_CPU0_SB_CA<4>
  VSS35  = GND
  CA6_B  = M_G_CPU0_SB_CA<6>
  VSS36  = GND
  CS0_B_N  = M_G_CPU0_SB_CS_N<0>
  VSS37  = GND
  \lbd||rsp_a_n\  = M_G_CPU0_SA_RSP<0>
  \lbs||rsp_b_n\  = M_G_CPU0_SB_RSP<0>
  VSS38  = GND
  CB4_B  = M_G_CPU0_SB_CB<4>
  VSS39  = GND
  CB5_B  = M_G_CPU0_SB_CB<5>
  VSS40  = GND
  \dqs9_b_t||tdqs9_b_t||dbi4_b_n\  = M_G_CPU0_SB_DQS_DP<9>
  \dqs9_b_c||tdqs9_b_c\  = M_G_CPU0_SB_DQS_DN<9>
  VSS41  = GND
  CB0_B  = M_G_CPU0_SB_CB<0>
  VSS42  = GND
  CB1_B  = M_G_CPU0_SB_CB<1>
  VSS43  = GND
  DQ0_B  = M_G_CPU0_SB_DQ<0>
  VSS44  = GND
  DQ1_B  = M_G_CPU0_SB_DQ<1>
  VSS45  = GND
  DQS0_B_T  = M_G_CPU0_SB_DQS_DP<0>
  DQS0_B_C  = M_G_CPU0_SB_DQS_DN<0>
  VSS46  = GND
  DQ4_B  = M_G_CPU0_SB_DQ<4>
  VSS47  = GND
  DQ5_B  = M_G_CPU0_SB_DQ<5>
  VSS48  = GND
  DQ8_B  = M_G_CPU0_SB_DQ<8>
  VSS49  = GND
  DQ9_B  = M_G_CPU0_SB_DQ<9>
  VSS50  = GND
  DQS1_B_T  = M_G_CPU0_SB_DQS_DP<1>
  DQS1_B_C  = M_G_CPU0_SB_DQS_DN<1>
  VSS51  = GND
  DQ12_B  = M_G_CPU0_SB_DQ<12>
  VSS52  = GND
  DQ13_B  = M_G_CPU0_SB_DQ<13>
  VSS53  = GND
  DQ16_B  = M_G_CPU0_SB_DQ<16>
  VSS54  = GND
  DQ17_B  = M_G_CPU0_SB_DQ<17>
  VSS55  = GND
  DQS2_B_T  = M_G_CPU0_SB_DQS_DP<2>
  DQS2_B_C  = M_G_CPU0_SB_DQS_DN<2>
  VSS56  = GND
  DQ20_B  = M_G_CPU0_SB_DQ<20>
  VSS57  = GND
  DQ21_B  = M_G_CPU0_SB_DQ<21>
  VSS58  = GND
  DQ24_B  = M_G_CPU0_SB_DQ<24>
  VSS59  = GND
  DQ25_B  = M_G_CPU0_SB_DQ<25>
  VSS60  = GND
  DQS3_B_T  = M_G_CPU0_SB_DQS_DP<3>
  DQS3_B_C  = M_G_CPU0_SB_DQS_DN<3>
  VSS61  = GND
  DQ28_B  = M_G_CPU0_SB_DQ<28>
  VSS62  = GND
  DQ29_B  = M_G_CPU0_SB_DQ<29>
  VSS63  = GND
  RFU1  = NC
  VIN_BULK1  = P12V_MEM_CPU0
  VIN_BULK2  = P12V_MEM_CPU0
  \pwr_good||fail_n\  = PWRGD_CHG_CPU0_DIMM0
  HAS  = PD_CHG_CPU0_DIMM0_SAA
  RFU2  = NC
  RFU3  = NC
  VSS64  = GND
  DQ2_A  = M_G_CPU0_SA_DQ<2>
  VSS65  = GND
  DQ3_A  = M_G_CPU0_SA_DQ<3>
  VSS66  = GND
  \dqs5_a_c||tdqs5_a_c||dqs5_a_t||tdqs5_a_t\  = M_G_CPU0_SA_DQS_DN<5>
  \dqs5_a_t||tdqs5_a_t\  = M_G_CPU0_SA_DQS_DP<5>
  VSS67  = GND
  DQ6_A  = M_G_CPU0_SA_DQ<6>
  VSS68  = GND
  DQ7_A  = M_G_CPU0_SA_DQ<7>
  VSS69  = GND
  DQ10_A  = M_G_CPU0_SA_DQ<10>
  VSS70  = GND
  DQ11_A  = M_G_CPU0_SA_DQ<11>
  VSS71  = GND
  \dqs6_a_c||tdqs6_a_c||dqs6_a_t||tdqs6_a_t\  = M_G_CPU0_SA_DQS_DN<6>
  \dqs6_a_t||tdqs6_a_t\  = M_G_CPU0_SA_DQS_DP<6>
  VSS72  = GND
  DQ14_A  = M_G_CPU0_SA_DQ<14>
  VSS73  = GND
  DQ15_A  = M_G_CPU0_SA_DQ<15>
  VSS74  = GND
  DQ18_A  = M_G_CPU0_SA_DQ<18>
  VSS75  = GND
  DQ19_A  = M_G_CPU0_SA_DQ<19>
  VSS76  = GND
  \dqs7_a_c||tdqs7_a_c\  = M_G_CPU0_SA_DQS_DN<7>
  \dqs7_a_t||tdqs7_a_t\  = M_G_CPU0_SA_DQS_DP<7>
  VSS77  = GND
  DQ22_A  = M_G_CPU0_SA_DQ<22>
  VSS78  = GND
  DQ23_A  = M_G_CPU0_SA_DQ<23>
  VSS79  = GND
  DQ26_A  = M_G_CPU0_SA_DQ<26>
  VSS80  = GND
  DQ27_A  = M_G_CPU0_SA_DQ<27>
  VSS81  = GND
  \dqs8_a_c||tdqs8_a_c\  = M_G_CPU0_SA_DQS_DN<8>
  \dqs8_a_t||tdqs8_a_t\  = M_G_CPU0_SA_DQS_DP<8>
  VSS82  = GND
  DQ30_A  = M_G_CPU0_SA_DQ<30>
  VSS83  = GND
  DQ31_A  = M_G_CPU0_SA_DQ<31>
  VSS84  = GND
  CB2_A  = M_G_CPU0_SA_CB<2>
  VSS85  = GND
  CB3_A  = M_G_CPU0_SA_CB<3>
  VSS86  = GND
  \dqs9_a_c||tdqs9_a_c\  = M_G_CPU0_SA_DQS_DN<9>
  \dqs9_a_t||tdqs9_a_t\  = M_G_CPU0_SA_DQS_DP<9>
  VSS87  = GND
  CB6_A  = M_G_CPU0_SA_CB<6>
  VSS88  = GND
  CB7_A  = M_G_CPU0_SA_CB<7>
  VSS89  = GND
  RESET_N  = M_G_CPU0_RESET_N
  VSS90  = GND
  CS1_A_N  = M_G_CPU0_SA_CS_N<1>
  VSS91  = GND
  CA1_A  = M_G_CPU0_SA_CA<1>
  VSS92  = GND
  CA3_A  = M_G_CPU0_SA_CA<3>
  VSS93  = GND
  CA5_A  = M_G_CPU0_SA_CA<5>
  VSS94  = GND
  CK_T  = M_G_CPU0_CLK_DP<0>
  CK_C  = M_G_CPU0_CLK_DN<0>
  VSS95  = GND
  RFU4  = NC
  CA1_B  = M_G_CPU0_SB_CA<1>
  VSS96  = GND
  CA3_B  = M_G_CPU0_SB_CA<3>
  VSS97  = GND
  CA5_B  = M_G_CPU0_SB_CA<5>
  VSS98  = GND
  PAR_B  = M_G_CPU0_SB_PAR
  VSS99  = GND
  CS1_B_N  = M_G_CPU0_SB_CS_N<1>
  VSS100  = GND
  RFU5  = NC
  RFU6  = NC
  VSS101  = GND
  CB6_B  = M_G_CPU0_SB_CB<6>
  VSS102  = GND
  CB7_B  = M_G_CPU0_SB_CB<7>
  VSS103  = GND
  DQS4_B_C  = M_G_CPU0_SB_DQS_DN<4>
  DQS4_B_T  = M_G_CPU0_SB_DQS_DP<4>
  VSS104  = GND
  CB2_B  = M_G_CPU0_SB_CB<2>
  VSS105  = GND
  CB3_B  = M_G_CPU0_SB_CB<3>
  VSS106  = GND
  DQ2_B  = M_G_CPU0_SB_DQ<2>
  VSS107  = GND
  DQ3_B  = M_G_CPU0_SB_DQ<3>
  VSS108  = GND
  \dqs5_b_c||tdqs5_b_c\  = M_G_CPU0_SB_DQS_DN<5>
  \dqs5_b_t||tdqs5_b_t\  = M_G_CPU0_SB_DQS_DP<5>
  VSS109  = GND
  DQ6_B  = M_G_CPU0_SB_DQ<6>
  VSS110  = GND
  DQ7_B  = M_G_CPU0_SB_DQ<7>
  VSS111  = GND
  DQ10_B  = M_G_CPU0_SB_DQ<10>
  VSS112  = GND
  DQ11_B  = M_G_CPU0_SB_DQ<11>
  VSS113  = GND
  \dqs6_b_c||tdqs6_b_c\  = M_G_CPU0_SB_DQS_DN<6>
  \dqs6_b_t||tdqs6_b_t\  = M_G_CPU0_SB_DQS_DP<6>
  VSS114  = GND
  DQ14_B  = M_G_CPU0_SB_DQ<14>
  VSS115  = GND
  DQ15_B  = M_G_CPU0_SB_DQ<15>
  VSS116  = GND
  DQ18_B  = M_G_CPU0_SB_DQ<18>
  VSS117  = GND
  DQ19_B  = M_G_CPU0_SB_DQ<19>
  VSS118  = GND
  \dqs7_b_c||tdqs7_b_c\  = M_G_CPU0_SB_DQS_DN<7>
  \dqs7_b_t||tdqs7_b_t\  = M_G_CPU0_SB_DQS_DP<7>
  VSS119  = GND
  DQ22_B  = M_G_CPU0_SB_DQ<22>
  VSS120  = GND
  DQ23_B  = M_G_CPU0_SB_DQ<23>
  VSS121  = GND
  DQ26_B  = M_G_CPU0_SB_DQ<26>
  VSS122  = GND
  DQ27_B  = M_G_CPU0_SB_DQ<27>
  VSS123  = GND
  \dqs8_b_c||tdqs8_b_c\  = M_G_CPU0_SB_DQS_DN<8>
  \dqs8_b_t||tdqs8_b_t\  = M_G_CPU0_SB_DQS_DP<8>
  VSS124  = GND
  DQ30_B  = M_G_CPU0_SB_DQ<30>
  VSS125  = GND
  DQ31_B  = M_G_CPU0_SB_DQ<31>
  VSS126  = GND
  G1  = GND
  G2  = GND
  G3  = GND

(kicad_pcb
	(version 20260206)
	(generator "pcbnew")
	(generator_version "10.0")
	(general
		(thickness 1.6)
		(legacy_teardrops no)
	)
	(paper "A4")
	(title_block
		(title "04192023_DAF0TMB3IC0_F0TG_MB_C_brd_V02_OCP.brd")
		(comment 1 "Grand Teton / footprint 1808 of 8354 (J16), pads 47-92 of 291")
	)
	(layers
		(0 "F.Cu" signal "TOP")
		(4 "In1.Cu" signal "GND")
		(6 "In2.Cu" signal "IN1")
		(8 "In3.Cu" signal "GND1")
		(10 "In4.Cu" signal "IN2")
		(12 "In5.Cu" signal "GND2")
		(14 "In6.Cu" signal "IN3")
		(16 "In7.Cu" signal "GND3")
		(18 "In8.Cu" signal "VCC")
		(20 "In9.Cu" signal "VCC1")
		(22 "In10.Cu" signal "GND4")
		(24 "In11.Cu" signal "IN4")
		(26 "In12.Cu" signal "GND5")
		(28 "In13.Cu" signal "IN5")
		(30 "In14.Cu" signal "GND6")
		(32 "In15.Cu" signal "IN6")
		(34 "In16.Cu" signal "GND7")
		(2 "B.Cu" signal "BOTTOM")
		(9 "F.Adhes" user "F.Adhesive")
		(11 "B.Adhes" user "B.Adhesive")
		(13 "F.Paste" user "Package Geometry/Pastemask Top")
		(15 "B.Paste" user "Package Geometry/Pastemask Bottom")
		(5 "F.SilkS" user "Ref Des/Silkscreen Top")
		(7 "B.SilkS" user "Ref Des/Silkscreen Bottom")
		(1 "F.Mask" user "Board Geometry/Soldermask Top")
		(3 "B.Mask" user "Board Geometry/Soldermask Bottom")
		(17 "Dwgs.User" user "User.Drawings")
		(19 "Cmts.User" user "User.Comments")
		(21 "Eco1.User" user "User.Eco1")
		(23 "Eco2.User" user "User.Eco2")
		(25 "Edge.Cuts" user "Board Geometry/Outline")
		(27 "Margin" user)
		(31 "F.CrtYd" user "Package Geometry/Place Bound Top")
		(29 "B.CrtYd" user "Package Geometry/Place Bound Bottom")
		(35 "F.Fab" user "Ref Des/Assembly Top")
		(33 "B.Fab" user "Ref Des/Assembly Bottom")
	)
	(footprint ""
		(layer "F.Cu")
		(at 414.418018 -255.560068 180)
		(property "Reference" "J16"
			(at 1.474216 81.889092 0)
			(unlocked yes)
			(layer "F.SilkS")
			(effects
				(font
					(size 0.7874 0.5842)
					(thickness 0.1524)
				)
			)
		)
		(property "Value" ""
			(at 0 0 180)
			(layer "F.Fab")
			(effects
				(font
					(size 1.27 1.27)
				)
			)
		)
		(duplicate_pad_numbers_are_jumpers no)
		(pad "47" smd rect
			(at -2.050034 -24.224996 90)
			(size 0.519938 1.4986)
			(layers "F.Cu" "F.Mask" "F.Paste")
			(net "M_G_CPU0_SA_DQ<28>")
		)
		(pad "48" smd rect
			(at -2.050034 -23.375112 90)
			(size 0.519938 1.4986)
			(layers "F.Cu" "F.Mask" "F.Paste")
			(net "GND")
		)
		(pad "49" smd rect
			(at -2.050034 -22.524974 90)
			(size 0.519938 1.4986)
			(layers "F.Cu" "F.Mask" "F.Paste")
			(net "M_G_CPU0_SA_DQ<29>")
		)
		(pad "50" smd rect
			(at -2.050034 -21.67509 90)
			(size 0.519938 1.4986)
			(layers "F.Cu" "F.Mask" "F.Paste")
			(net "GND")
		)
		(pad "51" smd rect
			(at -2.050034 -20.824952 90)
			(size 0.519938 1.4986)
			(layers "F.Cu" "F.Mask" "F.Paste")
			(net "M_G_CPU0_SA_CB<0>")
		)
		(pad "52" smd rect
			(at -2.050034 -19.975068 90)
			(size 0.519938 1.4986)
			(layers "F.Cu" "F.Mask" "F.Paste")
			(net "GND")
		)
		(pad "53" smd rect
			(at -2.050034 -19.12493 90)
			(size 0.519938 1.4986)
			(layers "F.Cu" "F.Mask" "F.Paste")
			(net "M_G_CPU0_SA_CB<1>")
		)
		(pad "54" smd rect
			(at -2.050034 -18.275046 90)
			(size 0.519938 1.4986)
			(layers "F.Cu" "F.Mask" "F.Paste")
			(net "GND")
		)
		(pad "55" smd rect
			(at -2.050034 -17.424908 90)
			(size 0.519938 1.4986)
			(layers "F.Cu" "F.Mask" "F.Paste")
			(net "M_G_CPU0_SA_DQS_DP<4>")
		)
		(pad "56" smd rect
			(at -2.050034 -16.575024 90)
			(size 0.519938 1.4986)
			(layers "F.Cu" "F.Mask" "F.Paste")
			(net "M_G_CPU0_SA_DQS_DN<4>")
		)
		(pad "57" smd rect
			(at -2.050034 -15.724886 90)
			(size 0.519938 1.4986)
			(layers "F.Cu" "F.Mask" "F.Paste")
			(net "GND")
		)
		(pad "58" smd rect
			(at -2.050034 -14.875002 90)
			(size 0.519938 1.4986)
			(layers "F.Cu" "F.Mask" "F.Paste")
			(net "M_G_CPU0_SA_CB<4>")
		)
		(pad "59" smd rect
			(at -2.050034 -14.025118 90)
			(size 0.519938 1.4986)
			(layers "F.Cu" "F.Mask" "F.Paste")
			(net "GND")
		)
		(pad "60" smd rect
			(at -2.050034 -13.17498 90)
			(size 0.519938 1.4986)
			(layers "F.Cu" "F.Mask" "F.Paste")
			(net "M_G_CPU0_SA_CB<5>")
		)
		(pad "61" smd rect
			(at -2.050034 -12.325096 90)
			(size 0.519938 1.4986)
			(layers "F.Cu" "F.Mask" "F.Paste")
			(net "GND")
		)
		(pad "62" smd rect
			(at -2.050034 -11.474958 90)
			(size 0.519938 1.4986)
			(layers "F.Cu" "F.Mask" "F.Paste")
			(net "M_G_CPU0_ALERT_N")
		)
		(pad "63" smd rect
			(at -2.050034 -10.625074 90)
			(size 0.519938 1.4986)
			(layers "F.Cu" "F.Mask" "F.Paste")
			(net "GND")
		)
		(pad "64" smd rect
			(at -2.050034 -9.774936 90)
			(size 0.519938 1.4986)
			(layers "F.Cu" "F.Mask" "F.Paste")
			(net "M_G_CPU0_SA_CS_N<0>")
		)
		(pad "65" smd rect
			(at -2.050034 -8.925052 90)
			(size 0.519938 1.4986)
			(layers "F.Cu" "F.Mask" "F.Paste")
			(net "GND")
		)
		(pad "66" smd rect
			(at -2.050034 -8.074914 90)
			(size 0.519938 1.4986)
			(layers "F.Cu" "F.Mask" "F.Paste")
			(net "M_G_CPU0_SA_CA<0>")
		)
		(pad "67" smd rect
			(at -2.050034 -7.22503 90)
			(size 0.519938 1.4986)
			(layers "F.Cu" "F.Mask" "F.Paste")
			(net "GND")
		)
		(pad "68" smd rect
			(at -2.050034 -6.374892 90)
			(size 0.519938 1.4986)
			(layers "F.Cu" "F.Mask" "F.Paste")
			(net "M_G_CPU0_SA_CA<2>")
		)
		(pad "69" smd rect
			(at -2.050034 -5.525008 90)
			(size 0.519938 1.4986)
			(layers "F.Cu" "F.Mask" "F.Paste")
			(net "GND")
		)
		(pad "70" smd rect
			(at -2.050034 -4.675124 90)
			(size 0.519938 1.4986)
			(layers "F.Cu" "F.Mask" "F.Paste")
			(net "M_G_CPU0_SA_CA<4>")
		)
		(pad "71" smd rect
			(at -2.050034 -3.824986 90)
			(size 0.519938 1.4986)
			(layers "F.Cu" "F.Mask" "F.Paste")
			(net "GND")
		)
		(pad "72" smd rect
			(at -2.050034 -2.975102 90)
			(size 0.519938 1.4986)
			(layers "F.Cu" "F.Mask" "F.Paste")
			(net "M_G_CPU0_SA_CA<6>")
		)
		(pad "73" smd rect
			(at -2.050034 -2.124964 90)
			(size 0.519938 1.4986)
			(layers "F.Cu" "F.Mask" "F.Paste")
			(net "GND")
		)
		(pad "74" smd rect
			(at -2.050034 -1.27508 90)
			(size 0.519938 1.4986)
			(layers "F.Cu" "F.Mask" "F.Paste")
			(net "M_G_CPU0_SA_PAR")
		)
		(pad "75" smd rect
			(at -2.050034 -0.424942 90)
			(size 0.519938 1.4986)
			(layers "F.Cu" "F.Mask" "F.Paste")
			(net "GND")
		)
		(pad "76" smd rect
			(at -2.050034 5.525008 90)
			(size 0.519938 1.4986)
			(layers "F.Cu" "F.Mask" "F.Paste")
			(net "M_G_CPU0_SB_CA<0>")
		)
		(pad "77" smd rect
			(at -2.050034 6.374892 90)
			(size 0.519938 1.4986)
			(layers "F.Cu" "F.Mask" "F.Paste")
			(net "GND")
		)
		(pad "78" smd rect
			(at -2.050034 7.22503 90)
			(size 0.519938 1.4986)
			(layers "F.Cu" "F.Mask" "F.Paste")
			(net "M_G_CPU0_SB_CA<2>")
		)
		(pad "79" smd rect
			(at -2.050034 8.074914 90)
			(size 0.519938 1.4986)
			(layers "F.Cu" "F.Mask" "F.Paste")
			(net "GND")
		)
		(pad "80" smd rect
			(at -2.050034 8.925052 90)
			(size 0.519938 1.4986)
			(layers "F.Cu" "F.Mask" "F.Paste")
			(net "M_G_CPU0_SB_CA<4>")
		)
		(pad "81" smd rect
			(at -2.050034 9.774936 90)
			(size 0.519938 1.4986)
			(layers "F.Cu" "F.Mask" "F.Paste")
			(net "GND")
		)
		(pad "82" smd rect
			(at -2.050034 10.625074 90)
			(size 0.519938 1.4986)
			(layers "F.Cu" "F.Mask" "F.Paste")
			(net "M_G_CPU0_SB_CA<6>")
		)
		(pad "83" smd rect
			(at -2.050034 11.474958 90)
			(size 0.519938 1.4986)
			(layers "F.Cu" "F.Mask" "F.Paste")
			(net "GND")
		)
		(pad "84" smd rect
			(at -2.050034 12.325096 90)
			(size 0.519938 1.4986)
			(layers "F.Cu" "F.Mask" "F.Paste")
			(net "M_G_CPU0_SB_CS_N<0>")
		)
		(pad "85" smd rect
			(at -2.050034 13.17498 90)
			(size 0.519938 1.4986)
			(layers "F.Cu" "F.Mask" "F.Paste")
			(net "GND")
		)
		(pad "86" smd rect
			(at -2.050034 14.025118 90)
			(size 0.519938 1.4986)
			(layers "F.Cu" "F.Mask" "F.Paste")
			(net "M_G_CPU0_SA_RSP<0>")
		)
		(pad "87" smd rect
			(at -2.050034 14.875002 90)
			(size 0.519938 1.4986)
			(layers "F.Cu" "F.Mask" "F.Paste")
			(net "M_G_CPU0_SB_RSP<0>")
		)
		(pad "88" smd rect
			(at -2.050034 15.724886 90)
			(size 0.519938 1.4986)
			(layers "F.Cu" "F.Mask" "F.Paste")
			(net "GND")
		)
		(pad "89" smd rect
			(at -2.050034 16.575024 90)
			(size 0.519938 1.4986)
			(layers "F.Cu" "F.Mask" "F.Paste")
			(net "M_G_CPU0_SB_CB<4>")
		)
		(pad "90" smd rect
			(at -2.050034 17.424908 90)
			(size 0.519938 1.4986)
			(layers "F.Cu" "F.Mask" "F.Paste")
			(net "GND")
		)
		(pad "91" smd rect
			(at -2.050034 18.275046 90)
			(size 0.519938 1.4986)
			(layers "F.Cu" "F.Mask" "F.Paste")
			(net "M_G_CPU0_SB_CB<5>")
		)
		(pad "92" smd rect
			(at -2.050034 19.12493 90)
			(size 0.519938 1.4986)
			(layers "F.Cu" "F.Mask" "F.Paste")
			(net "GND")
		)
	)
)
